# T6G (Grand Teton) — schematic netlist excerpt (pin names and nets, part order shuffled) for the footprints in the layout excerpt that follows; sources: Cadence DE-HDL packaged netlist, KiCad conversion of 04192023_DAF0TMB3IC0_F0TG_MB_C_brd_V02_OCP.brd

R8090  Q_RES  0 5% CHIP  pkg 0402LF  page 104 : A = PWRGD_CHGL_CPU1_R1 ; B = PWRGD_CHGL_CPU1_R2

(kicad_pcb
	(version 20260206)
	(generator "pcbnew")
	(generator_version "10.0")
	(general
		(thickness 1.6)
		(legacy_teardrops no)
	)
	(paper "A4")
	(title_block
		(title "04192023_DAF0TMB3IC0_F0TG_MB_C_brd_V02_OCP.brd")
		(comment 1 "Grand Teton / footprints 2928-2928 of 8354")
	)
	(layers
		(0 "F.Cu" signal "TOP")
		(4 "In1.Cu" signal "GND")
		(6 "In2.Cu" signal "IN1")
		(8 "In3.Cu" signal "GND1")
		(10 "In4.Cu" signal "IN2")
		(12 "In5.Cu" signal "GND2")
		(14 "In6.Cu" signal "IN3")
		(16 "In7.Cu" signal "GND3")
		(18 "In8.Cu" signal "VCC")
		(20 "In9.Cu" signal "VCC1")
		(22 "In10.Cu" signal "GND4")
		(24 "In11.Cu" signal "IN4")
		(26 "In12.Cu" signal "GND5")
		(28 "In13.Cu" signal "IN5")
		(30 "In14.Cu" signal "GND6")
		(32 "In15.Cu" signal "IN6")
		(34 "In16.Cu" signal "GND7")
		(2 "B.Cu" signal "BOTTOM")
		(9 "F.Adhes" user "F.Adhesive")
		(11 "B.Adhes" user "B.Adhesive")
		(13 "F.Paste" user "Package Geometry/Pastemask Top")
		(15 "B.Paste" user "Package Geometry/Pastemask Bottom")
		(5 "F.SilkS" user "Ref Des/Silkscreen Top")
		(7 "B.SilkS" user "Ref Des/Silkscreen Bottom")
		(1 "F.Mask" user "Board Geometry/Soldermask Top")
		(3 "B.Mask" user "Board Geometry/Soldermask Bottom")
		(17 "Dwgs.User" user "User.Drawings")
		(19 "Cmts.User" user "User.Comments")
		(21 "Eco1.User" user "User.Eco1")
		(23 "Eco2.User" user "User.Eco2")
		(25 "Edge.Cuts" user "Board Geometry/Outline")
		(27 "Margin" user)
		(31 "F.CrtYd" user "Package Geometry/Place Bound Top")
		(29 "B.CrtYd" user "Package Geometry/Place Bound Bottom")
		(35 "F.Fab" user "Ref Des/Assembly Top")
		(33 "B.Fab" user "Ref Des/Assembly Bottom")
	)
	(footprint ""
		(layer "F.Cu")
		(at 198.247 -93.345 180)
		(property "Reference" "R8090"
			(at 0 0 180)
			(layer "F.SilkS")
			(hide yes)
			(effects
				(font
					(size 1.27 1.27)
				)
			)
		)
		(property "Value" ""
			(at 0 0 180)
			(layer "F.Fab")
			(effects
				(font
					(size 1.27 1.27)
				)
			)
		)
		(duplicate_pad_numbers_are_jumpers no)
		(fp_line
			(start 0.7874 0.4064)
			(end -0.7874 0.4064)
			(stroke
				(width 0.1524)
				(type default)
			)
			(layer "F.SilkS")
		)
		(fp_line
			(start 0.7874 -0.4064)
			(end 0.7874 0.4064)
			(stroke
				(width 0.1524)
				(type default)
			)
			(layer "F.SilkS")
		)
		(fp_line
			(start -0.7874 0.4064)
			(end -0.7874 -0.4064)
			(stroke
				(width 0.1524)
				(type default)
			)
			(layer "F.SilkS")
		)
		(fp_line
			(start -0.7874 -0.4064)
			(end 0.7874 -0.4064)
			(stroke
				(width 0.1524)
				(type default)
			)
			(layer "F.SilkS")
		)
		(fp_line
			(start 0.67945 0.3048)
			(end 0.120396 0.3048)
			(stroke
				(width 0.1)
				(type default)
			)
			(layer "F.Fab")
		)
		(fp_line
			(start 0.67945 -0.3048)
			(end 0.67945 0.3048)
			(stroke
				(width 0.1)
				(type default)
			)
			(layer "F.Fab")
		)
		(fp_line
			(start 0.12065 -0.2794)
			(end 0.12065 -0.3048)
			(stroke
				(width 0.1)
				(type default)
			)
			(layer "F.Fab")
		)
		(fp_line
			(start 0.12065 -0.3048)
			(end 0.67945 -0.3048)
			(stroke
				(width 0.1)
				(type default)
			)
			(layer "F.Fab")
		)
		(fp_line
			(start 0.120396 0.3048)
			(end 0.120396 0.2794)
			(stroke
				(width 0.1)
				(type default)
			)
			(layer "F.Fab")
		)
		(fp_line
			(start 0.120396 0.2794)
			(end -0.12065 0.2794)
			(stroke
				(width 0.1)
				(type default)
			)
			(layer "F.Fab")
		)
		(fp_line
			(start -0.12065 0.3048)
			(end -0.67945 0.3048)
			(stroke
				(width 0.1)
				(type default)
			)
			(layer "F.Fab")
		)
		(fp_line
			(start -0.12065 0.2794)
			(end -0.12065 0.3048)
			(stroke
				(width 0.1)
				(type default)
			)
			(layer "F.Fab")
		)
		(fp_line
			(start -0.12065 -0.2794)
			(end 0.12065 -0.2794)
			(stroke
				(width 0.1)
				(type default)
			)
			(layer "F.Fab")
		)
		(fp_line
			(start -0.12065 -0.305054)
			(end -0.12065 -0.2794)
			(stroke
				(width 0.1)
				(type default)
			)
			(layer "F.Fab")
		)
		(fp_line
			(start -0.67945 0.3048)
			(end -0.67945 -0.305054)
			(stroke
				(width 0.1)
				(type default)
			)
			(layer "F.Fab")
		)
		(fp_line
			(start -0.67945 -0.305054)
			(end -0.12065 -0.305054)
			(stroke
				(width 0.1)
				(type default)
			)
			(layer "F.Fab")
		)
		(pad "1" smd circle
			(at -0.40005 0 180)
			(size 0 0)
			(layers "F.Cu" "F.Mask" "F.Paste")
			(net "PWRGD_CHGL_CPU1_R1")
		)
		(pad "2" smd circle
			(at 0.40005 0 180)
			(size 0 0)
			(layers "F.Cu" "F.Mask" "F.Paste")
			(net "PWRGD_CHGL_CPU1_R2")
		)
	)
)
